# T6G (Grand Teton) — schematic netlist excerpt (pin names and nets, part order shuffled) for the footprints in the layout excerpt that follows; sources: Cadence DE-HDL packaged netlist, KiCad conversion of 04192023_DAF0TMB3IC0_F0TG_MB_C_brd_V02_OCP.brd

PR600  Q_RES  4.99K 1% EMPTY  pkg 0402LF  page 200 : A = PVDDCR_CPU1_P0_VINSEN ; B = GND
C6659  Q_CAP_DIFFBUS  DIFF BUS_0.22UF 6.3V 20% X6S  pkg C0201  page 319 : \1\ = P5E_CPU1_P0_TX_BUF_C_DP<15> ; \2\ = P5E_CPU1_P0_TX_BUF_DP<15>
PR3960  Q_RES  160K 1% CHIP  pkg 0402LF  page 146 : A = P12V_AUX ; B = P12V_E1S_UV_0

(kicad_pcb
	(version 20260206)
	(generator "pcbnew")
	(generator_version "10.0")
	(general
		(thickness 1.6)
		(legacy_teardrops no)
	)
	(paper "A4")
	(title_block
		(title "04192023_DAF0TMB3IC0_F0TG_MB_C_brd_V02_OCP.brd")
		(comment 1 "Grand Teton / footprints 4528-4530 of 8354")
	)
	(layers
		(0 "F.Cu" signal "TOP")
		(4 "In1.Cu" signal "GND")
		(6 "In2.Cu" signal "IN1")
		(8 "In3.Cu" signal "GND1")
		(10 "In4.Cu" signal "IN2")
		(12 "In5.Cu" signal "GND2")
		(14 "In6.Cu" signal "IN3")
		(16 "In7.Cu" signal "GND3")
		(18 "In8.Cu" signal "VCC")
		(20 "In9.Cu" signal "VCC1")
		(22 "In10.Cu" signal "GND4")
		(24 "In11.Cu" signal "IN4")
		(26 "In12.Cu" signal "GND5")
		(28 "In13.Cu" signal "IN5")
		(30 "In14.Cu" signal "GND6")
		(32 "In15.Cu" signal "IN6")
		(34 "In16.Cu" signal "GND7")
		(2 "B.Cu" signal "BOTTOM")
		(9 "F.Adhes" user "F.Adhesive")
		(11 "B.Adhes" user "B.Adhesive")
		(13 "F.Paste" user "Package Geometry/Pastemask Top")
		(15 "B.Paste" user "Package Geometry/Pastemask Bottom")
		(5 "F.SilkS" user "Ref Des/Silkscreen Top")
		(7 "B.SilkS" user "Ref Des/Silkscreen Bottom")
		(1 "F.Mask" user "Board Geometry/Soldermask Top")
		(3 "B.Mask" user "Board Geometry/Soldermask Bottom")
		(17 "Dwgs.User" user "User.Drawings")
		(19 "Cmts.User" user "User.Comments")
		(21 "Eco1.User" user "User.Eco1")
		(23 "Eco2.User" user "User.Eco2")
		(25 "Edge.Cuts" user "Board Geometry/Outline")
		(27 "Margin" user)
		(31 "F.CrtYd" user "Package Geometry/Place Bound Top")
		(29 "B.CrtYd" user "Package Geometry/Place Bound Bottom")
		(35 "F.Fab" user "Ref Des/Assembly Top")
		(33 "B.Fab" user "Ref Des/Assembly Bottom")
	)
	(footprint ""
		(layer "F.Cu")
		(at 250.30303 -45.995082 -90)
		(property "Reference" "PR3960"
			(at 0 0 270)
			(layer "F.SilkS")
			(hide yes)
			(effects
				(font
					(size 1.27 1.27)
				)
			)
		)
		(property "Value" ""
			(at 0 0 270)
			(layer "F.Fab")
			(effects
				(font
					(size 1.27 1.27)
				)
			)
		)
		(duplicate_pad_numbers_are_jumpers no)
		(fp_line
			(start -0.7874 0.4064)
			(end -0.7874 -0.4064)
			(stroke
				(width 0.1524)
				(type default)
			)
			(layer "F.SilkS")
		)
		(fp_line
			(start 0.7874 0.4064)
			(end -0.7874 0.4064)
			(stroke
				(width 0.1524)
				(type default)
			)
			(layer "F.SilkS")
		)
		(fp_line
			(start -0.7874 -0.4064)
			(end 0.7874 -0.4064)
			(stroke
				(width 0.1524)
				(type default)
			)
			(layer "F.SilkS")
		)
		(fp_line
			(start 0.7874 -0.4064)
			(end 0.7874 0.4064)
			(stroke
				(width 0.1524)
				(type default)
			)
			(layer "F.SilkS")
		)
		(fp_line
			(start -0.67945 0.3048)
			(end -0.67945 -0.305054)
			(stroke
				(width 0.1)
				(type default)
			)
			(layer "F.Fab")
		)
		(fp_line
			(start -0.12065 0.3048)
			(end -0.67945 0.3048)
			(stroke
				(width 0.1)
				(type default)
			)
			(layer "F.Fab")
		)
		(fp_line
			(start 0.120396 0.3048)
			(end 0.120396 0.2794)
			(stroke
				(width 0.1)
				(type default)
			)
			(layer "F.Fab")
		)
		(fp_line
			(start 0.67945 0.3048)
			(end 0.120396 0.3048)
			(stroke
				(width 0.1)
				(type default)
			)
			(layer "F.Fab")
		)
		(fp_line
			(start -0.12065 0.2794)
			(end -0.12065 0.3048)
			(stroke
				(width 0.1)
				(type default)
			)
			(layer "F.Fab")
		)
		(fp_line
			(start 0.120396 0.2794)
			(end -0.12065 0.2794)
			(stroke
				(width 0.1)
				(type default)
			)
			(layer "F.Fab")
		)
		(fp_line
			(start -0.12065 -0.2794)
			(end 0.12065 -0.2794)
			(stroke
				(width 0.1)
				(type default)
			)
			(layer "F.Fab")
		)
		(fp_line
			(start 0.12065 -0.2794)
			(end 0.12065 -0.3048)
			(stroke
				(width 0.1)
				(type default)
			)
			(layer "F.Fab")
		)
		(fp_line
			(start 0.12065 -0.3048)
			(end 0.67945 -0.3048)
			(stroke
				(width 0.1)
				(type default)
			)
			(layer "F.Fab")
		)
		(fp_line
			(start 0.67945 -0.3048)
			(end 0.67945 0.3048)
			(stroke
				(width 0.1)
				(type default)
			)
			(layer "F.Fab")
		)
		(fp_line
			(start -0.67945 -0.305054)
			(end -0.12065 -0.305054)
			(stroke
				(width 0.1)
				(type default)
			)
			(layer "F.Fab")
		)
		(fp_line
			(start -0.12065 -0.305054)
			(end -0.12065 -0.2794)
			(stroke
				(width 0.1)
				(type default)
			)
			(layer "F.Fab")
		)
		(pad "1" smd circle
			(at -0.40005 0 270)
			(size 0 0)
			(layers "F.Cu" "F.Mask" "F.Paste")
			(net "P12V_AUX")
		)
		(pad "2" smd circle
			(at 0.40005 0 270)
			(size 0 0)
			(layers "F.Cu" "F.Mask" "F.Paste")
			(net "P12V_E1S_UV_0")
		)
	)
	(footprint ""
		(layer "F.Cu")
		(at 317.246 -362.839 90)
		(property "Reference" "PR600"
			(at 0 0 90)
			(layer "F.SilkS")
			(hide yes)
			(effects
				(font
					(size 1.27 1.27)
				)
			)
		)
		(property "Value" ""
			(at 0 0 90)
			(layer "F.Fab")
			(effects
				(font
					(size 1.27 1.27)
				)
			)
		)
		(duplicate_pad_numbers_are_jumpers no)
		(fp_line
			(start 0.7874 -0.4064)
			(end 0.7874 0.4064)
			(stroke
				(width 0.1524)
				(type default)
			)
			(layer "F.SilkS")
		)
		(fp_line
			(start -0.7874 -0.4064)
			(end 0.7874 -0.4064)
			(stroke
				(width 0.1524)
				(type default)
			)
			(layer "F.SilkS")
		)
		(fp_line
			(start 0.7874 0.4064)
			(end -0.7874 0.4064)
			(stroke
				(width 0.1524)
				(type default)
			)
			(layer "F.SilkS")
		)
		(fp_line
			(start -0.7874 0.4064)
			(end -0.7874 -0.4064)
			(stroke
				(width 0.1524)
				(type default)
			)
			(layer "F.SilkS")
		)
		(fp_line
			(start -0.12065 -0.305054)
			(end -0.12065 -0.2794)
			(stroke
				(width 0.1)
				(type default)
			)
			(layer "F.Fab")
		)
		(fp_line
			(start -0.67945 -0.305054)
			(end -0.12065 -0.305054)
			(stroke
				(width 0.1)
				(type default)
			)
			(layer "F.Fab")
		)
		(fp_line
			(start 0.67945 -0.3048)
			(end 0.67945 0.3048)
			(stroke
				(width 0.1)
				(type default)
			)
			(layer "F.Fab")
		)
		(fp_line
			(start 0.12065 -0.3048)
			(end 0.67945 -0.3048)
			(stroke
				(width 0.1)
				(type default)
			)
			(layer "F.Fab")
		)
		(fp_line
			(start 0.12065 -0.2794)
			(end 0.12065 -0.3048)
			(stroke
				(width 0.1)
				(type default)
			)
			(layer "F.Fab")
		)
		(fp_line
			(start -0.12065 -0.2794)
			(end 0.12065 -0.2794)
			(stroke
				(width 0.1)
				(type default)
			)
			(layer "F.Fab")
		)
		(fp_line
			(start 0.120396 0.2794)
			(end -0.12065 0.2794)
			(stroke
				(width 0.1)
				(type default)
			)
			(layer "F.Fab")
		)
		(fp_line
			(start -0.12065 0.2794)
			(end -0.12065 0.3048)
			(stroke
				(width 0.1)
				(type default)
			)
			(layer "F.Fab")
		)
		(fp_line
			(start 0.67945 0.3048)
			(end 0.120396 0.3048)
			(stroke
				(width 0.1)
				(type default)
			)
			(layer "F.Fab")
		)
		(fp_line
			(start 0.120396 0.3048)
			(end 0.120396 0.2794)
			(stroke
				(width 0.1)
				(type default)
			)
			(layer "F.Fab")
		)
		(fp_line
			(start -0.12065 0.3048)
			(end -0.67945 0.3048)
			(stroke
				(width 0.1)
				(type default)
			)
			(layer "F.Fab")
		)
		(fp_line
			(start -0.67945 0.3048)
			(end -0.67945 -0.305054)
			(stroke
				(width 0.1)
				(type default)
			)
			(layer "F.Fab")
		)
		(pad "1" smd circle
			(at -0.40005 0 90)
			(size 0 0)
			(layers "F.Cu" "F.Mask" "F.Paste")
			(net "PVDDCR_CPU1_P0_VINSEN")
		)
		(pad "2" smd circle
			(at 0.40005 0 90)
			(size 0 0)
			(layers "F.Cu" "F.Mask" "F.Paste")
			(net "GND")
		)
	)
	(footprint ""
		(layer "F.Cu")
		(at 94.631764 -408.517344 -90)
		(property "Reference" "C6659"
			(at 0 0 270)
			(layer "F.SilkS")
			(hide yes)
			(effects
				(font
					(size 1.27 1.27)
				)
			)
		)
		(property "Value" ""
			(at 0 0 270)
			(layer "F.Fab")
			(effects
				(font
					(size 1.27 1.27)
				)
			)
		)
		(duplicate_pad_numbers_are_jumpers no)
		(fp_line
			(start -0.299974 0.150114)
			(end -0.299974 -0.150114)
			(stroke
				(width 0.1)
				(type default)
			)
			(layer "F.Fab")
		)
		(fp_line
			(start 0.299974 0.150114)
			(end -0.299974 0.150114)
			(stroke
				(width 0.1)
				(type default)
			)
			(layer "F.Fab")
		)
		(fp_line
			(start -0.299974 -0.150114)
			(end 0.299974 -0.150114)
			(stroke
				(width 0.1)
				(type default)
			)
			(layer "F.Fab")
		)
		(fp_line
			(start 0.299974 -0.150114)
			(end 0.299974 0.150114)
			(stroke
				(width 0.1)
				(type default)
			)
			(layer "F.Fab")
		)
		(pad "1" smd rect
			(at -0.2667 0 270)
			(size 0.3048 0.381)
			(layers "F.Cu" "F.Mask" "F.Paste")
			(net "P5E_CPU1_P0_TX_BUF_C_DP<15>")
		)
		(pad "2" smd rect
			(at 0.2667 0 270)
			(size 0.3048 0.381)
			(layers "F.Cu" "F.Mask" "F.Paste")
			(net "P5E_CPU1_P0_TX_BUF_DP<15>")
		)
	)
)
